# S9S_MB_2U (Grand Teton) — schematic netlist excerpt (pin names and nets, part order shuffled) for the footprints in the layout excerpt that follows; sources: Cadence DE-HDL packaged netlist, KiCad conversion of 03242023_DA0F0TMBIJ0_F0T_Motherboard_J_brd_V01_OCP.brd

C1264  Q_CAP  1UF 6.3V 10% EMPTY  pkg 0402  page 189 : A = P1V05_PCH_PLL_AUX ; B = GND
PR4253  Q_RES  0 5% CHIP  pkg 0402LF  page 296 : A = NC_PVCCD_HV_CPU1_ACSP4 ; B = GND

(kicad_pcb
	(version 20260206)
	(generator "pcbnew")
	(generator_version "10.0")
	(general
		(thickness 1.6)
		(legacy_teardrops no)
	)
	(paper "A4")
	(title_block
		(title "03242023_DA0F0TMBIJ0_F0T_Motherboard_J_brd_V01_OCP.brd")
		(comment 1 "Grand Teton / footprints 4155-4156 of 6105")
	)
	(layers
		(0 "F.Cu" signal "TOP")
		(4 "In1.Cu" signal "GND")
		(6 "In2.Cu" signal "IN1")
		(8 "In3.Cu" signal "GND1")
		(10 "In4.Cu" signal "IN2")
		(12 "In5.Cu" signal "GND2")
		(14 "In6.Cu" signal "IN3")
		(16 "In7.Cu" signal "GND3")
		(18 "In8.Cu" signal "VCC")
		(20 "In9.Cu" signal "VCC1")
		(22 "In10.Cu" signal "GND4")
		(24 "In11.Cu" signal "IN4")
		(26 "In12.Cu" signal "GND5")
		(28 "In13.Cu" signal "IN5")
		(30 "In14.Cu" signal "GND6")
		(32 "In15.Cu" signal "IN6")
		(34 "In16.Cu" signal "GND7")
		(2 "B.Cu" signal "BOTTOM")
		(9 "F.Adhes" user "F.Adhesive")
		(11 "B.Adhes" user "B.Adhesive")
		(13 "F.Paste" user "Package Geometry/Pastemask Top")
		(15 "B.Paste" user "Package Geometry/Pastemask Bottom")
		(5 "F.SilkS" user "Ref Des/Silkscreen Top")
		(7 "B.SilkS" user "Ref Des/Silkscreen Bottom")
		(1 "F.Mask" user "Board Geometry/Soldermask Top")
		(3 "B.Mask" user "Board Geometry/Soldermask Bottom")
		(17 "Dwgs.User" user "User.Drawings")
		(19 "Cmts.User" user "User.Comments")
		(21 "Eco1.User" user "User.Eco1")
		(23 "Eco2.User" user "User.Eco2")
		(25 "Edge.Cuts" user "Board Geometry/Outline")
		(27 "Margin" user)
		(31 "F.CrtYd" user "Package Geometry/Place Bound Top")
		(29 "B.CrtYd" user "Package Geometry/Place Bound Bottom")
		(35 "F.Fab" user "Ref Des/Assembly Top")
		(33 "B.Fab" user "Ref Des/Assembly Bottom")
	)
	(footprint ""
		(layer "B.Cu")
		(at 338.016342 -50.678842 90)
		(property "Reference" "C1264"
			(at 0 0 90)
			(layer "B.SilkS")
			(hide yes)
			(effects
				(font
					(size 1.27 1.27)
				)
				(justify mirror)
			)
		)
		(property "Value" ""
			(at 0 0 90)
			(layer "B.Fab")
			(effects
				(font
					(size 1.27 1.27)
				)
				(justify mirror)
			)
		)
		(duplicate_pad_numbers_are_jumpers no)
		(fp_line
			(start 0.7874 -0.4064)
			(end -0.7874 -0.4064)
			(stroke
				(width 0.1524)
				(type default)
			)
			(layer "B.SilkS")
		)
		(fp_line
			(start -0.7874 -0.4064)
			(end -0.7874 0.4064)
			(stroke
				(width 0.1524)
				(type default)
			)
			(layer "B.SilkS")
		)
		(fp_line
			(start 0.7874 0.4064)
			(end 0.7874 -0.4064)
			(stroke
				(width 0.1524)
				(type default)
			)
			(layer "B.SilkS")
		)
		(fp_line
			(start -0.7874 0.4064)
			(end 0.7874 0.4064)
			(stroke
				(width 0.1524)
				(type default)
			)
			(layer "B.SilkS")
		)
		(fp_line
			(start 0.67945 -0.305054)
			(end 0.12065 -0.305054)
			(stroke
				(width 0.1)
				(type default)
			)
			(layer "B.Fab")
		)
		(fp_line
			(start 0.12065 -0.305054)
			(end 0.12065 -0.2794)
			(stroke
				(width 0.1)
				(type default)
			)
			(layer "B.Fab")
		)
		(fp_line
			(start -0.12065 -0.3048)
			(end -0.67945 -0.3048)
			(stroke
				(width 0.1)
				(type default)
			)
			(layer "B.Fab")
		)
		(fp_line
			(start -0.67945 -0.3048)
			(end -0.67945 0.3048)
			(stroke
				(width 0.1)
				(type default)
			)
			(layer "B.Fab")
		)
		(fp_line
			(start 0.12065 -0.2794)
			(end -0.12065 -0.2794)
			(stroke
				(width 0.1)
				(type default)
			)
			(layer "B.Fab")
		)
		(fp_line
			(start -0.12065 -0.2794)
			(end -0.12065 -0.3048)
			(stroke
				(width 0.1)
				(type default)
			)
			(layer "B.Fab")
		)
		(fp_line
			(start 0.12065 0.2794)
			(end 0.12065 0.3048)
			(stroke
				(width 0.1)
				(type default)
			)
			(layer "B.Fab")
		)
		(fp_line
			(start -0.120396 0.2794)
			(end 0.12065 0.2794)
			(stroke
				(width 0.1)
				(type default)
			)
			(layer "B.Fab")
		)
		(fp_line
			(start 0.67945 0.3048)
			(end 0.67945 -0.305054)
			(stroke
				(width 0.1)
				(type default)
			)
			(layer "B.Fab")
		)
		(fp_line
			(start 0.12065 0.3048)
			(end 0.67945 0.3048)
			(stroke
				(width 0.1)
				(type default)
			)
			(layer "B.Fab")
		)
		(fp_line
			(start -0.120396 0.3048)
			(end -0.120396 0.2794)
			(stroke
				(width 0.1)
				(type default)
			)
			(layer "B.Fab")
		)
		(fp_line
			(start -0.67945 0.3048)
			(end -0.120396 0.3048)
			(stroke
				(width 0.1)
				(type default)
			)
			(layer "B.Fab")
		)
		(pad "1" smd circle
			(at 0.40005 0 270)
			(size 0 0)
			(layers "B.Cu" "B.Mask" "B.Paste")
			(net "P1V05_PCH_PLL_AUX")
		)
		(pad "2" smd circle
			(at -0.40005 0 270)
			(size 0 0)
			(layers "B.Cu" "B.Mask" "B.Paste")
			(net "GND")
		)
	)
	(footprint ""
		(layer "B.Cu")
		(at 24.877522 -165.059106 180)
		(property "Reference" "PR4253"
			(at 0 0 0)
			(layer "B.SilkS")
			(hide yes)
			(effects
				(font
					(size 1.27 1.27)
				)
				(justify mirror)
			)
		)
		(property "Value" ""
			(at 0 0 0)
			(layer "B.Fab")
			(effects
				(font
					(size 1.27 1.27)
				)
				(justify mirror)
			)
		)
		(duplicate_pad_numbers_are_jumpers no)
		(fp_line
			(start 0.7874 0.4064)
			(end 0.7874 -0.4064)
			(stroke
				(width 0.1524)
				(type default)
			)
			(layer "B.SilkS")
		)
		(fp_line
			(start 0.7874 -0.4064)
			(end -0.7874 -0.4064)
			(stroke
				(width 0.1524)
				(type default)
			)
			(layer "B.SilkS")
		)
		(fp_line
			(start -0.7874 0.4064)
			(end 0.7874 0.4064)
			(stroke
				(width 0.1524)
				(type default)
			)
			(layer "B.SilkS")
		)
		(fp_line
			(start -0.7874 -0.4064)
			(end -0.7874 0.4064)
			(stroke
				(width 0.1524)
				(type default)
			)
			(layer "B.SilkS")
		)
		(fp_line
			(start 0.67945 0.3048)
			(end 0.67945 -0.305054)
			(stroke
				(width 0.1)
				(type default)
			)
			(layer "B.Fab")
		)
		(fp_line
			(start 0.67945 -0.305054)
			(end 0.12065 -0.305054)
			(stroke
				(width 0.1)
				(type default)
			)
			(layer "B.Fab")
		)
		(fp_line
			(start 0.12065 0.3048)
			(end 0.67945 0.3048)
			(stroke
				(width 0.1)
				(type default)
			)
			(layer "B.Fab")
		)
		(fp_line
			(start 0.12065 0.2794)
			(end 0.12065 0.3048)
			(stroke
				(width 0.1)
				(type default)
			)
			(layer "B.Fab")
		)
		(fp_line
			(start 0.12065 -0.2794)
			(end -0.12065 -0.2794)
			(stroke
				(width 0.1)
				(type default)
			)
			(layer "B.Fab")
		)
		(fp_line
			(start 0.12065 -0.305054)
			(end 0.12065 -0.2794)
			(stroke
				(width 0.1)
				(type default)
			)
			(layer "B.Fab")
		)
		(fp_line
			(start -0.120396 0.3048)
			(end -0.120396 0.2794)
			(stroke
				(width 0.1)
				(type default)
			)
			(layer "B.Fab")
		)
		(fp_line
			(start -0.120396 0.2794)
			(end 0.12065 0.2794)
			(stroke
				(width 0.1)
				(type default)
			)
			(layer "B.Fab")
		)
		(fp_line
			(start -0.12065 -0.2794)
			(end -0.12065 -0.3048)
			(stroke
				(width 0.1)
				(type default)
			)
			(layer "B.Fab")
		)
		(fp_line
			(start -0.12065 -0.3048)
			(end -0.67945 -0.3048)
			(stroke
				(width 0.1)
				(type default)
			)
			(layer "B.Fab")
		)
		(fp_line
			(start -0.67945 0.3048)
			(end -0.120396 0.3048)
			(stroke
				(width 0.1)
				(type default)
			)
			(layer "B.Fab")
		)
		(fp_line
			(start -0.67945 -0.3048)
			(end -0.67945 0.3048)
			(stroke
				(width 0.1)
				(type default)
			)
			(layer "B.Fab")
		)
		(pad "1" smd circle
			(at 0.40005 0)
			(size 0 0)
			(layers "B.Cu" "B.Mask" "B.Paste")
			(net "NC_PVCCD_HV_CPU1_ACSP4")
		)
		(pad "2" smd circle
			(at -0.40005 0)
			(size 0 0)
			(layers "B.Cu" "B.Mask" "B.Paste")
			(net "GND")
		)
	)
)
